(kicad_pcb
	(version 20260206)
	(generator "pcbnew")
	(generator_version "10.0")
	(general
		(thickness 1.6)
		(legacy_teardrops no)
	)
	(paper "A4")
	(title_block
		(title "12092022_DA0F0TMDCD0_F0T_Management_Board_D_brd_V3_OCP.brd")
		(comment 1 "Grand Teton / footprints 817-821 of 1440")
	)
	(layers
		(0 "F.Cu" signal "TOP")
		(4 "In1.Cu" signal "GND")
		(6 "In2.Cu" signal "IN1")
		(8 "In3.Cu" signal "GND1")
		(10 "In4.Cu" signal "IN2")
		(12 "In5.Cu" signal "VCC")
		(14 "In6.Cu" signal "VCC1")
		(16 "In7.Cu" signal "IN3")
		(18 "In8.Cu" signal "GND2")
		(20 "In9.Cu" signal "IN4")
		(22 "In10.Cu" signal "GND3")
		(2 "B.Cu" signal "BOTTOM")
		(9 "F.Adhes" user "F.Adhesive")
		(11 "B.Adhes" user "B.Adhesive")
		(13 "F.Paste" user "Package Geometry/Pastemask Top")
		(15 "B.Paste" user "Package Geometry/Pastemask Bottom")
		(5 "F.SilkS" user "Ref Des/Silkscreen Top")
		(7 "B.SilkS" user "Ref Des/Silkscreen Bottom")
		(1 "F.Mask" user "Board Geometry/Soldermask Top")
		(3 "B.Mask" user "Board Geometry/Soldermask Bottom")
		(17 "Dwgs.User" user "User.Drawings")
		(19 "Cmts.User" user "User.Comments")
		(21 "Eco1.User" user "User.Eco1")
		(23 "Eco2.User" user "User.Eco2")
		(25 "Edge.Cuts" user "Board Geometry/Outline")
		(27 "Margin" user)
		(31 "F.CrtYd" user "Package Geometry/Place Bound Top")
		(29 "B.CrtYd" user "Package Geometry/Place Bound Bottom")
		(35 "F.Fab" user "Ref Des/Assembly Top")
		(33 "B.Fab" user "Ref Des/Assembly Bottom")
	)
	(footprint ""
		(layer "B.Cu")
		(at 53.719476 -47.913036 90)
		(property "Reference" "C107"
			(at 0 0 90)
			(layer "B.SilkS")
			(hide yes)
			(effects
				(font
					(size 1.27 1.27)
				)
				(justify mirror)
			)
		)
		(property "Value" ""
			(at 0 0 90)
			(layer "B.Fab")
			(effects
				(font
					(size 1.27 1.27)
				)
				(justify mirror)
			)
		)
		(duplicate_pad_numbers_are_jumpers no)
		(fp_line
			(start 0.7874 -0.4064)
			(end -0.7874 -0.4064)
			(stroke
				(width 0.1524)
				(type default)
			)
			(layer "B.SilkS")
		)
		(fp_line
			(start -0.7874 -0.4064)
			(end -0.7874 0.4064)
			(stroke
				(width 0.1524)
				(type default)
			)
			(layer "B.SilkS")
		)
		(fp_line
			(start 0.7874 0.4064)
			(end 0.7874 -0.4064)
			(stroke
				(width 0.1524)
				(type default)
			)
			(layer "B.SilkS")
		)
		(fp_line
			(start -0.7874 0.4064)
			(end 0.7874 0.4064)
			(stroke
				(width 0.1524)
				(type default)
			)
			(layer "B.SilkS")
		)
		(fp_line
			(start 0.67945 -0.305054)
			(end 0.12065 -0.305054)
			(stroke
				(width 0.1)
				(type default)
			)
			(layer "B.Fab")
		)
		(fp_line
			(start 0.12065 -0.305054)
			(end 0.12065 -0.2794)
			(stroke
				(width 0.1)
				(type default)
			)
			(layer "B.Fab")
		)
		(fp_line
			(start -0.12065 -0.3048)
			(end -0.67945 -0.3048)
			(stroke
				(width 0.1)
				(type default)
			)
			(layer "B.Fab")
		)
		(fp_line
			(start -0.67945 -0.3048)
			(end -0.67945 0.3048)
			(stroke
				(width 0.1)
				(type default)
			)
			(layer "B.Fab")
		)
		(fp_line
			(start 0.12065 -0.2794)
			(end -0.12065 -0.2794)
			(stroke
				(width 0.1)
				(type default)
			)
			(layer "B.Fab")
		)
		(fp_line
			(start -0.12065 -0.2794)
			(end -0.12065 -0.3048)
			(stroke
				(width 0.1)
				(type default)
			)
			(layer "B.Fab")
		)
		(fp_line
			(start 0.12065 0.2794)
			(end 0.12065 0.3048)
			(stroke
				(width 0.1)
				(type default)
			)
			(layer "B.Fab")
		)
		(fp_line
			(start -0.120396 0.2794)
			(end 0.12065 0.2794)
			(stroke
				(width 0.1)
				(type default)
			)
			(layer "B.Fab")
		)
		(fp_line
			(start 0.67945 0.3048)
			(end 0.67945 -0.305054)
			(stroke
				(width 0.1)
				(type default)
			)
			(layer "B.Fab")
		)
		(fp_line
			(start 0.12065 0.3048)
			(end 0.67945 0.3048)
			(stroke
				(width 0.1)
				(type default)
			)
			(layer "B.Fab")
		)
		(fp_line
			(start -0.120396 0.3048)
			(end -0.120396 0.2794)
			(stroke
				(width 0.1)
				(type default)
			)
			(layer "B.Fab")
		)
		(fp_line
			(start -0.67945 0.3048)
			(end -0.120396 0.3048)
			(stroke
				(width 0.1)
				(type default)
			)
			(layer "B.Fab")
		)
		(pad "1" smd circle
			(at 0.40005 0 270)
			(size 0 0)
			(layers "B.Cu" "B.Mask" "B.Paste")
			(net "P1V2_AUX")
		)
		(pad "2" smd circle
			(at -0.40005 0 270)
			(size 0 0)
			(layers "B.Cu" "B.Mask" "B.Paste")
			(net "GND")
		)
	)
	(footprint ""
		(layer "B.Cu")
		(at 71.676768 -51.63185 90)
		(property "Reference" "C5"
			(at 0 0 90)
			(layer "B.SilkS")
			(hide yes)
			(effects
				(font
					(size 1.27 1.27)
				)
				(justify mirror)
			)
		)
		(property "Value" ""
			(at 0 0 90)
			(layer "B.Fab")
			(effects
				(font
					(size 1.27 1.27)
				)
				(justify mirror)
			)
		)
		(duplicate_pad_numbers_are_jumpers no)
		(fp_line
			(start 0.7874 -0.4064)
			(end -0.7874 -0.4064)
			(stroke
				(width 0.1524)
				(type default)
			)
			(layer "B.SilkS")
		)
		(fp_line
			(start -0.7874 -0.4064)
			(end -0.7874 0.4064)
			(stroke
				(width 0.1524)
				(type default)
			)
			(layer "B.SilkS")
		)
		(fp_line
			(start 0.7874 0.4064)
			(end 0.7874 -0.4064)
			(stroke
				(width 0.1524)
				(type default)
			)
			(layer "B.SilkS")
		)
		(fp_line
			(start -0.7874 0.4064)
			(end 0.7874 0.4064)
			(stroke
				(width 0.1524)
				(type default)
			)
			(layer "B.SilkS")
		)
		(fp_line
			(start 0.67945 -0.305054)
			(end 0.12065 -0.305054)
			(stroke
				(width 0.1)
				(type default)
			)
			(layer "B.Fab")
		)
		(fp_line
			(start 0.12065 -0.305054)
			(end 0.12065 -0.2794)
			(stroke
				(width 0.1)
				(type default)
			)
			(layer "B.Fab")
		)
		(fp_line
			(start -0.12065 -0.3048)
			(end -0.67945 -0.3048)
			(stroke
				(width 0.1)
				(type default)
			)
			(layer "B.Fab")
		)
		(fp_line
			(start -0.67945 -0.3048)
			(end -0.67945 0.3048)
			(stroke
				(width 0.1)
				(type default)
			)
			(layer "B.Fab")
		)
		(fp_line
			(start 0.12065 -0.2794)
			(end -0.12065 -0.2794)
			(stroke
				(width 0.1)
				(type default)
			)
			(layer "B.Fab")
		)
		(fp_line
			(start -0.12065 -0.2794)
			(end -0.12065 -0.3048)
			(stroke
				(width 0.1)
				(type default)
			)
			(layer "B.Fab")
		)
		(fp_line
			(start 0.12065 0.2794)
			(end 0.12065 0.3048)
			(stroke
				(width 0.1)
				(type default)
			)
			(layer "B.Fab")
		)
		(fp_line
			(start -0.120396 0.2794)
			(end 0.12065 0.2794)
			(stroke
				(width 0.1)
				(type default)
			)
			(layer "B.Fab")
		)
		(fp_line
			(start 0.67945 0.3048)
			(end 0.67945 -0.305054)
			(stroke
				(width 0.1)
				(type default)
			)
			(layer "B.Fab")
		)
		(fp_line
			(start 0.12065 0.3048)
			(end 0.67945 0.3048)
			(stroke
				(width 0.1)
				(type default)
			)
			(layer "B.Fab")
		)
		(fp_line
			(start -0.120396 0.3048)
			(end -0.120396 0.2794)
			(stroke
				(width 0.1)
				(type default)
			)
			(layer "B.Fab")
		)
		(fp_line
			(start -0.67945 0.3048)
			(end -0.120396 0.3048)
			(stroke
				(width 0.1)
				(type default)
			)
			(layer "B.Fab")
		)
		(pad "1" smd circle
			(at 0.40005 0 270)
			(size 0 0)
			(layers "B.Cu" "B.Mask" "B.Paste")
			(net "P1V2_AUX")
		)
		(pad "2" smd circle
			(at -0.40005 0 270)
			(size 0 0)
			(layers "B.Cu" "B.Mask" "B.Paste")
			(net "GND")
		)
	)
	(footprint ""
		(layer "B.Cu")
		(at 79.7814 -68.6562 90)
		(property "Reference" "U52"
			(at -0.2794 1.97993 270)
			(unlocked yes)
			(layer "B.SilkS")
			(effects
				(font
					(size 0.7874 0.5842)
					(thickness 0.1524)
				)
				(justify mirror)
			)
		)
		(property "Value" ""
			(at 0 0 90)
			(layer "B.Fab")
			(effects
				(font
					(size 1.27 1.27)
				)
				(justify mirror)
			)
		)
		(duplicate_pad_numbers_are_jumpers no)
		(fp_line
			(start 0.254 -1.1176)
			(end 1.7018 -1.1176)
			(stroke
				(width 0.1524)
				(type default)
			)
			(layer "B.SilkS")
		)
		(fp_line
			(start -0.254 -1.1176)
			(end 0 -0.7112)
			(stroke
				(width 0.1524)
				(type default)
			)
			(layer "B.SilkS")
		)
		(fp_line
			(start -1.7018 -1.1176)
			(end -0.254 -1.1176)
			(stroke
				(width 0.1524)
				(type default)
			)
			(layer "B.SilkS")
		)
		(fp_line
			(start -1.7018 -1.1176)
			(end -1.7018 1.1176)
			(stroke
				(width 0.1524)
				(type default)
			)
			(layer "B.SilkS")
		)
		(fp_line
			(start 0 -0.7112)
			(end 0.254 -1.1176)
			(stroke
				(width 0.1524)
				(type default)
			)
			(layer "B.SilkS")
		)
		(fp_line
			(start 1.7018 1.1176)
			(end 1.7018 -1.1176)
			(stroke
				(width 0.1524)
				(type default)
			)
			(layer "B.SilkS")
		)
		(fp_line
			(start -1.7018 1.1176)
			(end 1.7018 1.1176)
			(stroke
				(width 0.1524)
				(type default)
			)
			(layer "B.SilkS")
		)
		(fp_poly
			(pts
				(xy 1.8161 -0.675386) (xy 2.4003 -0.446786) (xy 2.4003 -0.878586)
			)
			(stroke
				(width 0)
				(type default)
			)
			(fill yes)
			(layer "B.SilkS")
		)
		(fp_line
			(start 0.254 -1.1176)
			(end 1.5494 -1.1176)
			(stroke
				(width 0.1)
				(type default)
			)
			(layer "B.Fab")
		)
		(fp_line
			(start -0.254 -1.1176)
			(end 0.254 -1.1176)
			(stroke
				(width 0.1)
				(type default)
			)
			(layer "B.Fab")
		)
		(fp_line
			(start -1.5494 -1.1176)
			(end -0.254 -1.1176)
			(stroke
				(width 0.1)
				(type default)
			)
			(layer "B.Fab")
		)
		(fp_line
			(start -1.5494 -1.1176)
			(end -1.5494 1.1176)
			(stroke
				(width 0.1)
				(type default)
			)
			(layer "B.Fab")
		)
		(fp_line
			(start 1.5494 1.1176)
			(end 1.5494 -1.1176)
			(stroke
				(width 0.1)
				(type default)
			)
			(layer "B.Fab")
		)
		(fp_line
			(start -1.5494 1.1176)
			(end 1.5494 1.1176)
			(stroke
				(width 0.1)
				(type default)
			)
			(layer "B.Fab")
		)
		(fp_poly
			(pts
				(xy 1.8161 -0.675386) (xy 2.4003 -0.446786) (xy 2.4003 -0.878586)
			)
			(stroke
				(width 0)
				(type default)
			)
			(fill yes)
			(layer "B.Fab")
		)
		(pad "1" smd rect
			(at 0.962406 -0.649986)
			(size 0.3302 1.1684)
			(layers "B.Cu" "B.Mask" "B.Paste")
			(net "PWRGD_P5V_AUX")
		)
		(pad "2" smd rect
			(at 0.962406 0)
			(size 0.3302 1.1684)
			(layers "B.Cu" "B.Mask" "B.Paste")
			(net "PWRGD_P3V3_RGM")
		)
		(pad "3" smd rect
			(at 0.962406 0.649986)
			(size 0.3302 1.1684)
			(layers "B.Cu" "B.Mask" "B.Paste")
			(net "GND")
		)
		(pad "4" smd rect
			(at -0.962406 0.649986)
			(size 0.3302 1.1684)
			(layers "B.Cu" "B.Mask" "B.Paste")
			(net "EN_P1V2_AUX")
		)
		(pad "5" smd rect
			(at -0.962406 -0.649986)
			(size 0.3302 1.1684)
			(layers "B.Cu" "B.Mask" "B.Paste")
			(net "P3V3_LDO")
		)
	)
	(footprint ""
		(layer "B.Cu")
		(at 112.014 -58.42 90)
		(property "Reference" "X2"
			(at 1.99263 2.8448 0)
			(unlocked yes)
			(layer "B.SilkS")
			(effects
				(font
					(size 0.7874 0.5842)
					(thickness 0.1524)
				)
				(justify left mirror)
			)
		)
		(property "Value" ""
			(at 0 0 90)
			(layer "B.Fab")
			(effects
				(font
					(size 1.27 1.27)
				)
				(justify mirror)
			)
		)
		(property "Device Type" "TP_TDR_4P_FTS_TH-TP_TDR_4P_DIPA"
			(at -1.30175 1.27 0)
			(unlocked yes)
			(layer "B.Fab")
			(hide yes)
			(effects
				(font
					(size 0.635 0.4064)
					(thickness 0.1524)
				)
				(justify mirror)
			)
		)
		(property "User Part Number" "N_A"
			(at -1.30175 1.27 0)
			(unlocked yes)
			(layer "Cmts.User")
			(hide yes)
			(effects
				(font
					(size 0.635 0.4064)
					(thickness 0.1524)
				)
				(justify mirror)
			)
		)
		(duplicate_pad_numbers_are_jumpers no)
		(fp_line
			(start 0 -1.27)
			(end 0 -0.635)
			(stroke
				(width 0.1524)
				(type default)
			)
			(layer "B.SilkS")
		)
		(fp_line
			(start -2.54 -1.27)
			(end 0 -1.27)
			(stroke
				(width 0.1524)
				(type default)
			)
			(layer "B.SilkS")
		)
		(fp_line
			(start -2.54 -1.1303)
			(end -2.54 -1.27)
			(stroke
				(width 0.1524)
				(type default)
			)
			(layer "B.SilkS")
		)
		(fp_line
			(start 0 0.635)
			(end 0 1.905)
			(stroke
				(width 0.1524)
				(type default)
			)
			(layer "B.SilkS")
		)
		(fp_line
			(start -2.54 1.4097)
			(end -2.54 1.1303)
			(stroke
				(width 0.1524)
				(type default)
			)
			(layer "B.SilkS")
		)
		(fp_line
			(start 0 3.175)
			(end 0 3.81)
			(stroke
				(width 0.1524)
				(type default)
			)
			(layer "B.SilkS")
		)
		(fp_line
			(start 0 3.81)
			(end -2.54 3.81)
			(stroke
				(width 0.1524)
				(type default)
			)
			(layer "B.SilkS")
		)
		(fp_line
			(start -2.54 3.81)
			(end -2.54 3.6703)
			(stroke
				(width 0.1524)
				(type default)
			)
			(layer "B.SilkS")
		)
		(fp_poly
			(pts
				(xy 0.761746 0) (xy 2.285746 -0.762) (xy 2.285746 0.762)
			)
			(stroke
				(width 0)
				(type default)
			)
			(fill yes)
			(layer "B.SilkS")
		)
		(fp_line
			(start 0 -1.27)
			(end 0 3.81)
			(stroke
				(width 0.1)
				(type default)
			)
			(layer "B.Fab")
		)
		(fp_line
			(start -2.54 -1.27)
			(end 0 -1.27)
			(stroke
				(width 0.1)
				(type default)
			)
			(layer "B.Fab")
		)
		(fp_line
			(start 0 3.81)
			(end -2.54 3.81)
			(stroke
				(width 0.1)
				(type default)
			)
			(layer "B.Fab")
		)
		(fp_line
			(start -2.54 3.81)
			(end -2.54 -1.27)
			(stroke
				(width 0.1)
				(type default)
			)
			(layer "B.Fab")
		)
		(fp_poly
			(pts
				(xy 0.761746 0) (xy 2.285746 -0.762) (xy 2.285746 0.762)
			)
			(stroke
				(width 0)
				(type default)
			)
			(fill yes)
			(layer "B.Fab")
		)
		(pad "1" thru_hole circle
			(at 0 0 270)
			(size 1.0033 1.0033)
			(drill 0.249936)
			(layers "*.Cu" "*.Mask")
			(remove_unused_layers no)
			(net "TDR_DIFF_85_IN1_DP")
			(clearance 0.10795)
			(padstack
				(mode front_inner_back)
				(layer "Inner"
					(shape circle)
					(size 0.8001 0.8001)
					(clearance 0.1524)
				)
				(layer "B.Cu"
					(shape circle)
					(size 1.0033 1.0033)
					(thermal_gap 0.10795)
					(clearance 0.10795)
				)
			)
		)
		(pad "2" thru_hole circle
			(at -2.54 0 270)
			(size 1.9939 1.9939)
			(drill 0.249936)
			(layers "*.Cu" "*.Mask")
			(remove_unused_layers no)
			(net "GND_P1")
			(clearance 0.10795)
			(padstack
				(mode front_inner_back)
				(layer "Inner"
					(shape circle)
					(size 0.8001 0.8001)
					(clearance 0.1524)
				)
				(layer "B.Cu"
					(shape circle)
					(size 1.9939 1.9939)
					(thermal_gap 0.10795)
					(clearance 0.10795)
				)
			)
		)
		(pad "3" thru_hole circle
			(at -2.54 2.54 270)
			(size 1.9939 1.9939)
			(drill 0.249936)
			(layers "*.Cu" "*.Mask")
			(remove_unused_layers no)
			(net "GND_P1")
			(clearance 0.10795)
			(padstack
				(mode front_inner_back)
				(layer "Inner"
					(shape circle)
					(size 0.8001 0.8001)
					(clearance 0.1524)
				)
				(layer "B.Cu"
					(shape circle)
					(size 1.9939 1.9939)
					(thermal_gap 0.10795)
					(clearance 0.10795)
				)
			)
		)
		(pad "4" thru_hole circle
			(at 0 2.54 270)
			(size 1.0033 1.0033)
			(drill 0.249936)
			(layers "*.Cu" "*.Mask")
			(remove_unused_layers no)
			(net "TDR_DIFF_85_IN1_DN")
			(clearance 0.10795)
			(padstack
				(mode front_inner_back)
				(layer "Inner"
					(shape circle)
					(size 0.8001 0.8001)
					(clearance 0.1524)
				)
				(layer "B.Cu"
					(shape circle)
					(size 1.0033 1.0033)
					(thermal_gap 0.10795)
					(clearance 0.10795)
				)
			)
		)
	)
	(footprint ""
		(layer "B.Cu")
		(at 31.9532 -59.6392)
		(property "Reference" "R786"
			(at 0 0 0)
			(layer "B.SilkS")
			(hide yes)
			(effects
				(font
					(size 1.27 1.27)
				)
				(justify mirror)
			)
		)
		(property "Value" ""
			(at 0 0 0)
			(layer "B.Fab")
			(effects
				(font
					(size 1.27 1.27)
				)
				(justify mirror)
			)
		)
		(duplicate_pad_numbers_are_jumpers no)
		(fp_line
			(start -0.7874 -0.4064)
			(end -0.7874 0.4064)
			(stroke
				(width 0.1524)
				(type default)
			)
			(layer "B.SilkS")
		)
		(fp_line
			(start -0.7874 0.4064)
			(end 0.7874 0.4064)
			(stroke
				(width 0.1524)
				(type default)
			)
			(layer "B.SilkS")
		)
		(fp_line
			(start 0.7874 -0.4064)
			(end -0.7874 -0.4064)
			(stroke
				(width 0.1524)
				(type default)
			)
			(layer "B.SilkS")
		)
		(fp_line
			(start 0.7874 0.4064)
			(end 0.7874 -0.4064)
			(stroke
				(width 0.1524)
				(type default)
			)
			(layer "B.SilkS")
		)
		(fp_line
			(start -0.67945 -0.3048)
			(end -0.67945 0.3048)
			(stroke
				(width 0.1)
				(type default)
			)
			(layer "B.Fab")
		)
		(fp_line
			(start -0.67945 0.3048)
			(end -0.120396 0.3048)
			(stroke
				(width 0.1)
				(type default)
			)
			(layer "B.Fab")
		)
		(fp_line
			(start -0.12065 -0.3048)
			(end -0.67945 -0.3048)
			(stroke
				(width 0.1)
				(type default)
			)
			(layer "B.Fab")
		)
		(fp_line
			(start -0.12065 -0.2794)
			(end -0.12065 -0.3048)
			(stroke
				(width 0.1)
				(type default)
			)
			(layer "B.Fab")
		)
		(fp_line
			(start -0.120396 0.2794)
			(end 0.12065 0.2794)
			(stroke
				(width 0.1)
				(type default)
			)
			(layer "B.Fab")
		)
		(fp_line
			(start -0.120396 0.3048)
			(end -0.120396 0.2794)
			(stroke
				(width 0.1)
				(type default)
			)
			(layer "B.Fab")
		)
		(fp_line
			(start 0.12065 -0.305054)
			(end 0.12065 -0.2794)
			(stroke
				(width 0.1)
				(type default)
			)
			(layer "B.Fab")
		)
		(fp_line
			(start 0.12065 -0.2794)
			(end -0.12065 -0.2794)
			(stroke
				(width 0.1)
				(type default)
			)
			(layer "B.Fab")
		)
		(fp_line
			(start 0.12065 0.2794)
			(end 0.12065 0.3048)
			(stroke
				(width 0.1)
				(type default)
			)
			(layer "B.Fab")
		)
		(fp_line
			(start 0.12065 0.3048)
			(end 0.67945 0.3048)
			(stroke
				(width 0.1)
				(type default)
			)
			(layer "B.Fab")
		)
		(fp_line
			(start 0.67945 -0.305054)
			(end 0.12065 -0.305054)
			(stroke
				(width 0.1)
				(type default)
			)
			(layer "B.Fab")
		)
		(fp_line
			(start 0.67945 0.3048)
			(end 0.67945 -0.305054)
			(stroke
				(width 0.1)
				(type default)
			)
			(layer "B.Fab")
		)
		(pad "1" smd circle
			(at 0.40005 0 180)
			(size 0 0)
			(layers "B.Cu" "B.Mask" "B.Paste")
			(net "P12V_SENSOR")
		)
		(pad "2" smd circle
			(at -0.40005 0 180)
			(size 0 0)
			(layers "B.Cu" "B.Mask" "B.Paste")
			(net "GND")
		)
	)
)
